# T6G (Grand Teton) — schematic netlist excerpt (pin names and nets, part order shuffled) for the footprints in the layout excerpt that follows; sources: Cadence DE-HDL packaged netlist, KiCad conversion of 04192023_DAF0TMB3IC0_F0TG_MB_C_brd_V02_OCP.brd

PR401  Q_RES  0 5% CHIP  pkg 0402LF  page 226 : A = PVDD18_SS_P1_RGND ; B = VSENSE_PVDD18_S5_P1_DN
C960  Q_CAP_DIFFBUS  DIFF BUS_0.22UF 6.3V 20% X6S  pkg C0201  page 63 : \1\ = P5E_CPU0_P1_TX_C_DN<2> ; \2\ = P5E_CPU0_P1_TX_DN<2>
R701  Q_RES  200 1% CHIP  pkg 0201LF  page 321 : A = RT_CPU1_P0_VQPS ; B = GND

(kicad_pcb
	(version 20260206)
	(generator "pcbnew")
	(generator_version "10.0")
	(general
		(thickness 1.6)
		(legacy_teardrops no)
	)
	(paper "A4")
	(title_block
		(title "04192023_DAF0TMB3IC0_F0TG_MB_C_brd_V02_OCP.brd")
		(comment 1 "Grand Teton / footprints 1377-1379 of 8354")
	)
	(layers
		(0 "F.Cu" signal "TOP")
		(4 "In1.Cu" signal "GND")
		(6 "In2.Cu" signal "IN1")
		(8 "In3.Cu" signal "GND1")
		(10 "In4.Cu" signal "IN2")
		(12 "In5.Cu" signal "GND2")
		(14 "In6.Cu" signal "IN3")
		(16 "In7.Cu" signal "GND3")
		(18 "In8.Cu" signal "VCC")
		(20 "In9.Cu" signal "VCC1")
		(22 "In10.Cu" signal "GND4")
		(24 "In11.Cu" signal "IN4")
		(26 "In12.Cu" signal "GND5")
		(28 "In13.Cu" signal "IN5")
		(30 "In14.Cu" signal "GND6")
		(32 "In15.Cu" signal "IN6")
		(34 "In16.Cu" signal "GND7")
		(2 "B.Cu" signal "BOTTOM")
		(9 "F.Adhes" user "F.Adhesive")
		(11 "B.Adhes" user "B.Adhesive")
		(13 "F.Paste" user "Package Geometry/Pastemask Top")
		(15 "B.Paste" user "Package Geometry/Pastemask Bottom")
		(5 "F.SilkS" user "Ref Des/Silkscreen Top")
		(7 "B.SilkS" user "Ref Des/Silkscreen Bottom")
		(1 "F.Mask" user "Board Geometry/Soldermask Top")
		(3 "B.Mask" user "Board Geometry/Soldermask Bottom")
		(17 "Dwgs.User" user "User.Drawings")
		(19 "Cmts.User" user "User.Comments")
		(21 "Eco1.User" user "User.Eco1")
		(23 "Eco2.User" user "User.Eco2")
		(25 "Edge.Cuts" user "Board Geometry/Outline")
		(27 "Margin" user)
		(31 "F.CrtYd" user "Package Geometry/Place Bound Top")
		(29 "B.CrtYd" user "Package Geometry/Place Bound Bottom")
		(35 "F.Fab" user "Ref Des/Assembly Top")
		(33 "B.Fab" user "Ref Des/Assembly Bottom")
	)
	(footprint ""
		(layer "F.Cu")
		(at 332.431644 -381.41783 -90)
		(property "Reference" "C960"
			(at 0 0 270)
			(layer "F.SilkS")
			(hide yes)
			(effects
				(font
					(size 1.27 1.27)
				)
			)
		)
		(property "Value" ""
			(at 0 0 270)
			(layer "F.Fab")
			(effects
				(font
					(size 1.27 1.27)
				)
			)
		)
		(duplicate_pad_numbers_are_jumpers no)
		(fp_line
			(start -0.299974 0.150114)
			(end -0.299974 -0.150114)
			(stroke
				(width 0.1)
				(type default)
			)
			(layer "F.Fab")
		)
		(fp_line
			(start 0.299974 0.150114)
			(end -0.299974 0.150114)
			(stroke
				(width 0.1)
				(type default)
			)
			(layer "F.Fab")
		)
		(fp_line
			(start -0.299974 -0.150114)
			(end 0.299974 -0.150114)
			(stroke
				(width 0.1)
				(type default)
			)
			(layer "F.Fab")
		)
		(fp_line
			(start 0.299974 -0.150114)
			(end 0.299974 0.150114)
			(stroke
				(width 0.1)
				(type default)
			)
			(layer "F.Fab")
		)
		(pad "1" smd rect
			(at -0.2667 0 270)
			(size 0.3048 0.381)
			(layers "F.Cu" "F.Mask" "F.Paste")
			(net "P5E_CPU0_P1_TX_C_DN<2>")
		)
		(pad "2" smd rect
			(at 0.2667 0 270)
			(size 0.3048 0.381)
			(layers "F.Cu" "F.Mask" "F.Paste")
			(net "P5E_CPU0_P1_TX_DN<2>")
		)
	)
	(footprint ""
		(layer "F.Cu")
		(at 64.63538 -394.78966 -90)
		(property "Reference" "R701"
			(at 0 0 270)
			(layer "F.SilkS")
			(hide yes)
			(effects
				(font
					(size 1.27 1.27)
				)
			)
		)
		(property "Value" ""
			(at 0 0 270)
			(layer "F.Fab")
			(effects
				(font
					(size 1.27 1.27)
				)
			)
		)
		(duplicate_pad_numbers_are_jumpers no)
		(fp_line
			(start -0.32512 0.175006)
			(end -0.32512 -0.175006)
			(stroke
				(width 0.1)
				(type default)
			)
			(layer "F.Fab")
		)
		(fp_line
			(start 0.32512 0.175006)
			(end -0.32512 0.175006)
			(stroke
				(width 0.1)
				(type default)
			)
			(layer "F.Fab")
		)
		(fp_line
			(start -0.32512 -0.175006)
			(end 0.32512 -0.175006)
			(stroke
				(width 0.1)
				(type default)
			)
			(layer "F.Fab")
		)
		(fp_line
			(start 0.32512 -0.175006)
			(end 0.32512 0.175006)
			(stroke
				(width 0.1)
				(type default)
			)
			(layer "F.Fab")
		)
		(pad "1" smd rect
			(at -0.2667 0 270)
			(size 0.3048 0.381)
			(layers "F.Cu" "F.Mask" "F.Paste")
			(net "RT_CPU1_P0_VQPS")
		)
		(pad "2" smd rect
			(at 0.2667 0 90)
			(size 0.3048 0.381)
			(layers "F.Cu" "F.Mask" "F.Paste")
			(net "GND")
		)
	)
	(footprint ""
		(layer "F.Cu")
		(at 70.720204 -144.881092 180)
		(property "Reference" "PR401"
			(at 0 0 180)
			(layer "F.SilkS")
			(hide yes)
			(effects
				(font
					(size 1.27 1.27)
				)
			)
		)
		(property "Value" ""
			(at 0 0 180)
			(layer "F.Fab")
			(effects
				(font
					(size 1.27 1.27)
				)
			)
		)
		(duplicate_pad_numbers_are_jumpers no)
		(fp_line
			(start 0.7874 0.4064)
			(end -0.7874 0.4064)
			(stroke
				(width 0.1524)
				(type default)
			)
			(layer "F.SilkS")
		)
		(fp_line
			(start 0.7874 -0.4064)
			(end 0.7874 0.4064)
			(stroke
				(width 0.1524)
				(type default)
			)
			(layer "F.SilkS")
		)
		(fp_line
			(start -0.7874 0.4064)
			(end -0.7874 -0.4064)
			(stroke
				(width 0.1524)
				(type default)
			)
			(layer "F.SilkS")
		)
		(fp_line
			(start -0.7874 -0.4064)
			(end 0.7874 -0.4064)
			(stroke
				(width 0.1524)
				(type default)
			)
			(layer "F.SilkS")
		)
		(fp_line
			(start 0.67945 0.3048)
			(end 0.120396 0.3048)
			(stroke
				(width 0.1)
				(type default)
			)
			(layer "F.Fab")
		)
		(fp_line
			(start 0.67945 -0.3048)
			(end 0.67945 0.3048)
			(stroke
				(width 0.1)
				(type default)
			)
			(layer "F.Fab")
		)
		(fp_line
			(start 0.12065 -0.2794)
			(end 0.12065 -0.3048)
			(stroke
				(width 0.1)
				(type default)
			)
			(layer "F.Fab")
		)
		(fp_line
			(start 0.12065 -0.3048)
			(end 0.67945 -0.3048)
			(stroke
				(width 0.1)
				(type default)
			)
			(layer "F.Fab")
		)
		(fp_line
			(start 0.120396 0.3048)
			(end 0.120396 0.2794)
			(stroke
				(width 0.1)
				(type default)
			)
			(layer "F.Fab")
		)
		(fp_line
			(start 0.120396 0.2794)
			(end -0.12065 0.2794)
			(stroke
				(width 0.1)
				(type default)
			)
			(layer "F.Fab")
		)
		(fp_line
			(start -0.12065 0.3048)
			(end -0.67945 0.3048)
			(stroke
				(width 0.1)
				(type default)
			)
			(layer "F.Fab")
		)
		(fp_line
			(start -0.12065 0.2794)
			(end -0.12065 0.3048)
			(stroke
				(width 0.1)
				(type default)
			)
			(layer "F.Fab")
		)
		(fp_line
			(start -0.12065 -0.2794)
			(end 0.12065 -0.2794)
			(stroke
				(width 0.1)
				(type default)
			)
			(layer "F.Fab")
		)
		(fp_line
			(start -0.12065 -0.305054)
			(end -0.12065 -0.2794)
			(stroke
				(width 0.1)
				(type default)
			)
			(layer "F.Fab")
		)
		(fp_line
			(start -0.67945 0.3048)
			(end -0.67945 -0.305054)
			(stroke
				(width 0.1)
				(type default)
			)
			(layer "F.Fab")
		)
		(fp_line
			(start -0.67945 -0.305054)
			(end -0.12065 -0.305054)
			(stroke
				(width 0.1)
				(type default)
			)
			(layer "F.Fab")
		)
		(pad "1" smd circle
			(at -0.40005 0 180)
			(size 0 0)
			(layers "F.Cu" "F.Mask" "F.Paste")
			(net "PVDD18_SS_P1_RGND")
		)
		(pad "2" smd circle
			(at 0.40005 0 180)
			(size 0 0)
			(layers "F.Cu" "F.Mask" "F.Paste")
			(net "VSENSE_PVDD18_S5_P1_DN")
		)
	)
)
